(kicad_pcb
	(version 20260206)
	(generator "pcbnew")
	(generator_version "10.0")
	(general
		(thickness 1.6)
		(legacy_teardrops no)
	)
	(paper "A4")
	(title_block
		(title "panther-plus-userver — 13130-1b_20150205.brd")
		(comment 1 "Honey Badger (Wiwynn) / footprint 894 of 1509 (DIMM1), pads 65-71 of 210")
	)
	(layers
		(0 "F.Cu" signal "TOP")
		(4 "In1.Cu" signal "L2")
		(6 "In2.Cu" signal "L3")
		(8 "In3.Cu" signal "L4")
		(10 "In4.Cu" signal "L5")
		(12 "In5.Cu" signal "L6")
		(14 "In6.Cu" signal "L7")
		(16 "In7.Cu" signal "L8")
		(18 "In8.Cu" signal "L9")
		(20 "In9.Cu" signal "L10")
		(22 "In10.Cu" signal "L11")
		(2 "B.Cu" signal "BOTTOM")
		(9 "F.Adhes" user "F.Adhesive")
		(11 "B.Adhes" user "B.Adhesive")
		(13 "F.Paste" user "Package Geometry/Pastemask Top")
		(15 "B.Paste" user "Package Geometry/Pastemask Bottom")
		(5 "F.SilkS" user "Ref Des/Silkscreen Top")
		(7 "B.SilkS" user "Ref Des/Silkscreen Bottom")
		(1 "F.Mask" user "Board Geometry/Soldermask Top")
		(3 "B.Mask" user "Board Geometry/Soldermask Bottom")
		(17 "Dwgs.User" user "User.Drawings")
		(19 "Cmts.User" user "User.Comments")
		(21 "Eco1.User" user "User.Eco1")
		(23 "Eco2.User" user "User.Eco2")
		(25 "Edge.Cuts" user "Board Geometry/Outline")
		(27 "Margin" user)
		(31 "F.CrtYd" user "Package Geometry/Place Bound Top")
		(29 "B.CrtYd" user "Package Geometry/Place Bound Bottom")
		(35 "F.Fab" user "Ref Des/Assembly Top")
		(33 "B.Fab" user "Ref Des/Assembly Bottom")
	)
	(footprint ""
		(layer "B.Cu")
		(at 158.500064 -66.699892 180)
		(property "Reference" "DIMM1"
			(at 0 0 0)
			(layer "B.SilkS")
			(hide yes)
			(effects
				(font
					(size 1.27 1.27)
				)
				(justify mirror)
			)
		)
		(property "Value" "DDR3-204P-142-COLAY-1-GP-U"
			(at 41.312338 -16.676878 180)
			(unlocked yes)
			(layer "B.Fab")
			(hide yes)
			(effects
				(font
					(size 1.016 1.016)
					(thickness 0.1524)
				)
				(justify mirror)
			)
		)
		(property "Device Type" "AS0A626-J8R6-7H-COLAY-1"
			(at 41.312338 -18.200878 180)
			(unlocked yes)
			(layer "B.Fab")
			(hide yes)
			(effects
				(font
					(size 1.016 1.016)
					(thickness 0.1524)
				)
				(justify mirror)
			)
		)
		(duplicate_pad_numbers_are_jumpers no)
		(pad "63" smd custom
			(at -13.050012 -4.100068)
			(size 0.1143 0.1143)
			(layers "B.Cu" "B.Mask" "B.Paste")
			(net "M_A_DQ26")
			(options
				(clearance outline)
				(anchor circle)
			)
			(primitives
				(gr_poly
					(pts
						(xy 0 -0.9017) (xy -0.03175 -0.89916) (xy -0.0635 -0.889) (xy -0.09144 -0.87376) (xy -0.11684 -0.85344)
						(xy -0.13716 -0.82804) (xy -0.1524 -0.8001) (xy -0.16256 -0.76835) (xy -0.1651 -0.7366) (xy -0.1651 -0.19685)
						(xy -0.17272 -0.18923) (xy -0.17907 -0.18034) (xy -0.18669 -0.17145) (xy -0.19177 -0.16256) (xy -0.19812 -0.15367)
						(xy -0.20828 -0.13335) (xy -0.21971 -0.10287) (xy -0.22225 -0.09271) (xy -0.22479 -0.08128) (xy -0.22606 -0.07112)
						(xy -0.2286 -0.05969) (xy -0.2286 -0.01651) (xy -0.22606 -0.00508) (xy -0.22479 0.00508) (xy -0.22225 0.01651)
						(xy -0.21971 0.02667) (xy -0.20828 0.05715) (xy -0.19812 0.07747) (xy -0.19177 0.08636) (xy -0.18669 0.09525)
						(xy -0.17907 0.10414) (xy -0.17272 0.11303) (xy -0.1651 0.12065) (xy -0.1651 0.7366) (xy -0.16256 0.76835)
						(xy -0.1524 0.8001) (xy -0.13716 0.82804) (xy -0.11684 0.85344) (xy -0.09144 0.87376) (xy -0.0635 0.889)
						(xy -0.03175 0.89916) (xy 0 0.9017) (xy 0.03175 0.89916) (xy 0.0635 0.889) (xy 0.09144 0.87376)
						(xy 0.11684 0.85344) (xy 0.13716 0.82804) (xy 0.1524 0.8001) (xy 0.16256 0.76835) (xy 0.1651 0.7366)
						(xy 0.1651 0.11938) (xy 0.17272 0.11176) (xy 0.19812 0.0762) (xy 0.2032 0.06604) (xy 0.20701 0.05715)
						(xy 0.21209 0.04699) (xy 0.2159 0.03683) (xy 0.21844 0.02667) (xy 0.22225 0.01524) (xy 0.22352 0.00508)
						(xy 0.22606 -0.00508) (xy 0.22733 -0.01651) (xy 0.22733 -0.02667) (xy 0.2286 -0.0381) (xy 0.22733 -0.04953)
						(xy 0.22733 -0.05969) (xy 0.22606 -0.07112) (xy 0.22352 -0.08128) (xy 0.22225 -0.09144) (xy 0.21844 -0.10287)
						(xy 0.2159 -0.11303) (xy 0.21209 -0.12319) (xy 0.20701 -0.13335) (xy 0.2032 -0.14224) (xy 0.19812 -0.1524)
						(xy 0.17272 -0.18796) (xy 0.1651 -0.19558) (xy 0.1651 -0.7366) (xy 0.16256 -0.76835) (xy 0.1524 -0.8001)
						(xy 0.13716 -0.82804) (xy 0.11684 -0.85344) (xy 0.09144 -0.87376) (xy 0.0635 -0.889) (xy 0.03175 -0.89916)
					)
					(width 0)
					(fill yes)
				)
			)
		)
		(pad "64" smd custom
			(at -12.750038 4.100068)
			(size 0.1143 0.1143)
			(layers "B.Cu" "B.Mask" "B.Paste")
			(net "GND")
			(options
				(clearance outline)
				(anchor circle)
			)
			(primitives
				(gr_poly
					(pts
						(xy 0 -0.9017) (xy -0.03175 -0.89916) (xy -0.0635 -0.889) (xy -0.09144 -0.87376) (xy -0.11684 -0.85344)
						(xy -0.13716 -0.82804) (xy -0.1524 -0.8001) (xy -0.16256 -0.76835) (xy -0.1651 -0.7366) (xy -0.1651 -0.11938)
						(xy -0.17272 -0.11176) (xy -0.19812 -0.0762) (xy -0.2032 -0.06604) (xy -0.20701 -0.05715) (xy -0.21209 -0.04699)
						(xy -0.2159 -0.03683) (xy -0.21844 -0.02667) (xy -0.22225 -0.01524) (xy -0.22352 -0.00508) (xy -0.22606 0.00508)
						(xy -0.22733 0.01651) (xy -0.22733 0.02667) (xy -0.2286 0.0381) (xy -0.22733 0.04953) (xy -0.22733 0.05969)
						(xy -0.22606 0.07112) (xy -0.22352 0.08128) (xy -0.22225 0.09144) (xy -0.21844 0.10287) (xy -0.2159 0.11303)
						(xy -0.21209 0.12319) (xy -0.20701 0.13335) (xy -0.2032 0.14224) (xy -0.19812 0.1524) (xy -0.17272 0.18796)
						(xy -0.1651 0.19558) (xy -0.1651 0.7366) (xy -0.16256 0.76835) (xy -0.1524 0.8001) (xy -0.13716 0.82804)
						(xy -0.11684 0.85344) (xy -0.09144 0.87376) (xy -0.0635 0.889) (xy -0.03175 0.89916) (xy 0 0.9017)
						(xy 0.03175 0.89916) (xy 0.0635 0.889) (xy 0.09144 0.87376) (xy 0.11684 0.85344) (xy 0.13716 0.82804)
						(xy 0.1524 0.8001) (xy 0.16256 0.76835) (xy 0.1651 0.7366) (xy 0.1651 0.19685) (xy 0.17272 0.18923)
						(xy 0.17907 0.18034) (xy 0.18669 0.17145) (xy 0.19177 0.16256) (xy 0.19812 0.15367) (xy 0.20828 0.13335)
						(xy 0.21971 0.10287) (xy 0.22225 0.09271) (xy 0.22479 0.08128) (xy 0.22606 0.07112) (xy 0.2286 0.05969)
						(xy 0.2286 0.01651) (xy 0.22606 0.00508) (xy 0.22479 -0.00508) (xy 0.22225 -0.01651) (xy 0.21971 -0.02667)
						(xy 0.20828 -0.05715) (xy 0.19812 -0.07747) (xy 0.19177 -0.08636) (xy 0.18669 -0.09525) (xy 0.17907 -0.10414)
						(xy 0.17272 -0.11303) (xy 0.1651 -0.12065) (xy 0.1651 -0.7366) (xy 0.16256 -0.76835) (xy 0.1524 -0.8001)
						(xy 0.13716 -0.82804) (xy 0.11684 -0.85344) (xy 0.09144 -0.87376) (xy 0.0635 -0.889) (xy 0.03175 -0.89916)
					)
					(width 0)
					(fill yes)
				)
			)
		)
		(pad "65" smd custom
			(at -12.450064 -4.100068)
			(size 0.1143 0.1143)
			(layers "B.Cu" "B.Mask" "B.Paste")
			(net "M_A_DQ27")
			(options
				(clearance outline)
				(anchor circle)
			)
			(primitives
				(gr_poly
					(pts
						(xy 0 -0.9017) (xy -0.03175 -0.89916) (xy -0.0635 -0.889) (xy -0.09144 -0.87376) (xy -0.11684 -0.85344)
						(xy -0.13716 -0.82804) (xy -0.1524 -0.8001) (xy -0.16256 -0.76835) (xy -0.1651 -0.7366) (xy -0.1651 -0.44958)
						(xy -0.17272 -0.44196) (xy -0.19812 -0.4064) (xy -0.2032 -0.39624) (xy -0.20701 -0.38735) (xy -0.21209 -0.37719)
						(xy -0.2159 -0.36703) (xy -0.21844 -0.35687) (xy -0.22225 -0.34544) (xy -0.22352 -0.33528) (xy -0.22606 -0.32512)
						(xy -0.22733 -0.31369) (xy -0.22733 -0.30353) (xy -0.2286 -0.2921) (xy -0.22733 -0.28067) (xy -0.22733 -0.27051)
						(xy -0.22606 -0.25908) (xy -0.22352 -0.24892) (xy -0.22225 -0.23876) (xy -0.21844 -0.22733) (xy -0.2159 -0.21717)
						(xy -0.21209 -0.20701) (xy -0.20701 -0.19685) (xy -0.2032 -0.18796) (xy -0.19812 -0.1778) (xy -0.17272 -0.14224)
						(xy -0.1651 -0.13462) (xy -0.1651 0.7366) (xy -0.16256 0.76835) (xy -0.1524 0.8001) (xy -0.13716 0.82804)
						(xy -0.11684 0.85344) (xy -0.09144 0.87376) (xy -0.0635 0.889) (xy -0.03175 0.89916) (xy 0 0.9017)
						(xy 0.03175 0.89916) (xy 0.0635 0.889) (xy 0.09144 0.87376) (xy 0.11684 0.85344) (xy 0.13716 0.82804)
						(xy 0.1524 0.8001) (xy 0.16256 0.76835) (xy 0.1651 0.7366) (xy 0.1651 -0.13462) (xy 0.17272 -0.14224)
						(xy 0.19812 -0.1778) (xy 0.2032 -0.18796) (xy 0.20701 -0.19685) (xy 0.21209 -0.20701) (xy 0.2159 -0.21717)
						(xy 0.21844 -0.22733) (xy 0.22225 -0.23876) (xy 0.22352 -0.24892) (xy 0.22606 -0.25908) (xy 0.22733 -0.27051)
						(xy 0.22733 -0.28067) (xy 0.2286 -0.2921) (xy 0.22733 -0.30353) (xy 0.22733 -0.31369) (xy 0.22606 -0.32512)
						(xy 0.22352 -0.33528) (xy 0.22225 -0.34544) (xy 0.21844 -0.35687) (xy 0.2159 -0.36703) (xy 0.21209 -0.37719)
						(xy 0.20701 -0.38735) (xy 0.2032 -0.39624) (xy 0.19812 -0.4064) (xy 0.17272 -0.44196) (xy 0.1651 -0.44958)
						(xy 0.1651 -0.7366) (xy 0.16256 -0.76835) (xy 0.1524 -0.8001) (xy 0.13716 -0.82804) (xy 0.11684 -0.85344)
						(xy 0.09144 -0.87376) (xy 0.0635 -0.889) (xy 0.03175 -0.89916)
					)
					(width 0)
					(fill yes)
				)
			)
		)
		(pad "66" smd custom
			(at -12.15009 4.100068)
			(size 0.1143 0.1143)
			(layers "B.Cu" "B.Mask" "B.Paste")
			(net "M_A_DQ30")
			(options
				(clearance outline)
				(anchor circle)
			)
			(primitives
				(gr_poly
					(pts
						(xy 0 -0.9017) (xy -0.03175 -0.89916) (xy -0.0635 -0.889) (xy -0.09144 -0.87376) (xy -0.11684 -0.85344)
						(xy -0.13716 -0.82804) (xy -0.1524 -0.8001) (xy -0.16256 -0.76835) (xy -0.1651 -0.7366) (xy -0.1651 0.13462)
						(xy -0.17272 0.14224) (xy -0.19812 0.1778) (xy -0.2032 0.18796) (xy -0.20701 0.19685) (xy -0.21209 0.20701)
						(xy -0.2159 0.21717) (xy -0.21844 0.22733) (xy -0.22225 0.23876) (xy -0.22352 0.24892) (xy -0.22606 0.25908)
						(xy -0.22733 0.27051) (xy -0.22733 0.28067) (xy -0.2286 0.2921) (xy -0.22733 0.30353) (xy -0.22733 0.31369)
						(xy -0.22606 0.32512) (xy -0.22352 0.33528) (xy -0.22225 0.34544) (xy -0.21844 0.35687) (xy -0.2159 0.36703)
						(xy -0.21209 0.37719) (xy -0.20701 0.38735) (xy -0.2032 0.39624) (xy -0.19812 0.4064) (xy -0.17272 0.44196)
						(xy -0.1651 0.44958) (xy -0.1651 0.7366) (xy -0.16256 0.76835) (xy -0.1524 0.8001) (xy -0.13716 0.82804)
						(xy -0.11684 0.85344) (xy -0.09144 0.87376) (xy -0.0635 0.889) (xy -0.03175 0.89916) (xy 0 0.9017)
						(xy 0.03175 0.89916) (xy 0.0635 0.889) (xy 0.09144 0.87376) (xy 0.11684 0.85344) (xy 0.13716 0.82804)
						(xy 0.1524 0.8001) (xy 0.16256 0.76835) (xy 0.1651 0.7366) (xy 0.1651 0.44958) (xy 0.17272 0.44196)
						(xy 0.19812 0.4064) (xy 0.2032 0.39624) (xy 0.20701 0.38735) (xy 0.21209 0.37719) (xy 0.2159 0.36703)
						(xy 0.21844 0.35687) (xy 0.22225 0.34544) (xy 0.22352 0.33528) (xy 0.22606 0.32512) (xy 0.22733 0.31369)
						(xy 0.22733 0.30353) (xy 0.2286 0.2921) (xy 0.22733 0.28067) (xy 0.22733 0.27051) (xy 0.22606 0.25908)
						(xy 0.22352 0.24892) (xy 0.22225 0.23876) (xy 0.21844 0.22733) (xy 0.2159 0.21717) (xy 0.21209 0.20701)
						(xy 0.20701 0.19685) (xy 0.2032 0.18796) (xy 0.19812 0.1778) (xy 0.17272 0.14224) (xy 0.1651 0.13462)
						(xy 0.1651 -0.7366) (xy 0.16256 -0.76835) (xy 0.1524 -0.8001) (xy 0.13716 -0.82804) (xy 0.11684 -0.85344)
						(xy 0.09144 -0.87376) (xy 0.0635 -0.889) (xy 0.03175 -0.89916)
					)
					(width 0)
					(fill yes)
				)
			)
		)
		(pad "67" smd custom
			(at -11.850116 -4.100068)
			(size 0.1143 0.1143)
			(layers "B.Cu" "B.Mask" "B.Paste")
			(net "GND")
			(options
				(clearance outline)
				(anchor circle)
			)
			(primitives
				(gr_poly
					(pts
						(xy 0 -0.9017) (xy -0.03175 -0.89916) (xy -0.0635 -0.889) (xy -0.09144 -0.87376) (xy -0.11684 -0.85344)
						(xy -0.13716 -0.82804) (xy -0.1524 -0.8001) (xy -0.16256 -0.76835) (xy -0.1651 -0.7366) (xy -0.1651 -0.19685)
						(xy -0.17272 -0.18923) (xy -0.17907 -0.18034) (xy -0.18669 -0.17145) (xy -0.19177 -0.16256) (xy -0.19812 -0.15367)
						(xy -0.20828 -0.13335) (xy -0.21971 -0.10287) (xy -0.22225 -0.09271) (xy -0.22479 -0.08128) (xy -0.22606 -0.07112)
						(xy -0.2286 -0.05969) (xy -0.2286 -0.01651) (xy -0.22606 -0.00508) (xy -0.22479 0.00508) (xy -0.22225 0.01651)
						(xy -0.21971 0.02667) (xy -0.20828 0.05715) (xy -0.19812 0.07747) (xy -0.19177 0.08636) (xy -0.18669 0.09525)
						(xy -0.17907 0.10414) (xy -0.17272 0.11303) (xy -0.1651 0.12065) (xy -0.1651 0.7366) (xy -0.16256 0.76835)
						(xy -0.1524 0.8001) (xy -0.13716 0.82804) (xy -0.11684 0.85344) (xy -0.09144 0.87376) (xy -0.0635 0.889)
						(xy -0.03175 0.89916) (xy 0 0.9017) (xy 0.03175 0.89916) (xy 0.0635 0.889) (xy 0.09144 0.87376)
						(xy 0.11684 0.85344) (xy 0.13716 0.82804) (xy 0.1524 0.8001) (xy 0.16256 0.76835) (xy 0.1651 0.7366)
						(xy 0.1651 0.11938) (xy 0.17272 0.11176) (xy 0.19812 0.0762) (xy 0.2032 0.06604) (xy 0.20701 0.05715)
						(xy 0.21209 0.04699) (xy 0.2159 0.03683) (xy 0.21844 0.02667) (xy 0.22225 0.01524) (xy 0.22352 0.00508)
						(xy 0.22606 -0.00508) (xy 0.22733 -0.01651) (xy 0.22733 -0.02667) (xy 0.2286 -0.0381) (xy 0.22733 -0.04953)
						(xy 0.22733 -0.05969) (xy 0.22606 -0.07112) (xy 0.22352 -0.08128) (xy 0.22225 -0.09144) (xy 0.21844 -0.10287)
						(xy 0.2159 -0.11303) (xy 0.21209 -0.12319) (xy 0.20701 -0.13335) (xy 0.2032 -0.14224) (xy 0.19812 -0.1524)
						(xy 0.17272 -0.18796) (xy 0.1651 -0.19558) (xy 0.1651 -0.7366) (xy 0.16256 -0.76835) (xy 0.1524 -0.8001)
						(xy 0.13716 -0.82804) (xy 0.11684 -0.85344) (xy 0.09144 -0.87376) (xy 0.0635 -0.889) (xy 0.03175 -0.89916)
					)
					(width 0)
					(fill yes)
				)
			)
		)
		(pad "68" smd custom
			(at -11.549888 4.100068)
			(size 0.1143 0.1143)
			(layers "B.Cu" "B.Mask" "B.Paste")
			(net "M_A_DQ31")
			(options
				(clearance outline)
				(anchor circle)
			)
			(primitives
				(gr_poly
					(pts
						(xy 0 -0.9017) (xy -0.03175 -0.89916) (xy -0.0635 -0.889) (xy -0.09144 -0.87376) (xy -0.11684 -0.85344)
						(xy -0.13716 -0.82804) (xy -0.1524 -0.8001) (xy -0.16256 -0.76835) (xy -0.1651 -0.7366) (xy -0.1651 -0.11938)
						(xy -0.17272 -0.11176) (xy -0.19812 -0.0762) (xy -0.2032 -0.06604) (xy -0.20701 -0.05715) (xy -0.21209 -0.04699)
						(xy -0.2159 -0.03683) (xy -0.21844 -0.02667) (xy -0.22225 -0.01524) (xy -0.22352 -0.00508) (xy -0.22606 0.00508)
						(xy -0.22733 0.01651) (xy -0.22733 0.02667) (xy -0.2286 0.0381) (xy -0.22733 0.04953) (xy -0.22733 0.05969)
						(xy -0.22606 0.07112) (xy -0.22352 0.08128) (xy -0.22225 0.09144) (xy -0.21844 0.10287) (xy -0.2159 0.11303)
						(xy -0.21209 0.12319) (xy -0.20701 0.13335) (xy -0.2032 0.14224) (xy -0.19812 0.1524) (xy -0.17272 0.18796)
						(xy -0.1651 0.19558) (xy -0.1651 0.7366) (xy -0.16256 0.76835) (xy -0.1524 0.8001) (xy -0.13716 0.82804)
						(xy -0.11684 0.85344) (xy -0.09144 0.87376) (xy -0.0635 0.889) (xy -0.03175 0.89916) (xy 0 0.9017)
						(xy 0.03175 0.89916) (xy 0.0635 0.889) (xy 0.09144 0.87376) (xy 0.11684 0.85344) (xy 0.13716 0.82804)
						(xy 0.1524 0.8001) (xy 0.16256 0.76835) (xy 0.1651 0.7366) (xy 0.1651 0.19685) (xy 0.17272 0.18923)
						(xy 0.17907 0.18034) (xy 0.18669 0.17145) (xy 0.19177 0.16256) (xy 0.19812 0.15367) (xy 0.20828 0.13335)
						(xy 0.21971 0.10287) (xy 0.22225 0.09271) (xy 0.22479 0.08128) (xy 0.22606 0.07112) (xy 0.2286 0.05969)
						(xy 0.2286 0.01651) (xy 0.22606 0.00508) (xy 0.22479 -0.00508) (xy 0.22225 -0.01651) (xy 0.21971 -0.02667)
						(xy 0.20828 -0.05715) (xy 0.19812 -0.07747) (xy 0.19177 -0.08636) (xy 0.18669 -0.09525) (xy 0.17907 -0.10414)
						(xy 0.17272 -0.11303) (xy 0.1651 -0.12065) (xy 0.1651 -0.7366) (xy 0.16256 -0.76835) (xy 0.1524 -0.8001)
						(xy 0.13716 -0.82804) (xy 0.11684 -0.85344) (xy 0.09144 -0.87376) (xy 0.0635 -0.889) (xy 0.03175 -0.89916)
					)
					(width 0)
					(fill yes)
				)
			)
		)
		(pad "69" smd custom
			(at -11.249914 -4.100068)
			(size 0.1143 0.1143)
			(layers "B.Cu" "B.Mask" "B.Paste")
			(net "M_A_ECC0")
			(options
				(clearance outline)
				(anchor circle)
			)
			(primitives
				(gr_poly
					(pts
						(xy 0 -0.9017) (xy -0.03175 -0.89916) (xy -0.0635 -0.889) (xy -0.09144 -0.87376) (xy -0.11684 -0.85344)
						(xy -0.13716 -0.82804) (xy -0.1524 -0.8001) (xy -0.16256 -0.76835) (xy -0.1651 -0.7366) (xy -0.1651 -0.44958)
						(xy -0.17272 -0.44196) (xy -0.19812 -0.4064) (xy -0.2032 -0.39624) (xy -0.20701 -0.38735) (xy -0.21209 -0.37719)
						(xy -0.2159 -0.36703) (xy -0.21844 -0.35687) (xy -0.22225 -0.34544) (xy -0.22352 -0.33528) (xy -0.22606 -0.32512)
						(xy -0.22733 -0.31369) (xy -0.22733 -0.30353) (xy -0.2286 -0.2921) (xy -0.22733 -0.28067) (xy -0.22733 -0.27051)
						(xy -0.22606 -0.25908) (xy -0.22352 -0.24892) (xy -0.22225 -0.23876) (xy -0.21844 -0.22733) (xy -0.2159 -0.21717)
						(xy -0.21209 -0.20701) (xy -0.20701 -0.19685) (xy -0.2032 -0.18796) (xy -0.19812 -0.1778) (xy -0.17272 -0.14224)
						(xy -0.1651 -0.13462) (xy -0.1651 0.7366) (xy -0.16256 0.76835) (xy -0.1524 0.8001) (xy -0.13716 0.82804)
						(xy -0.11684 0.85344) (xy -0.09144 0.87376) (xy -0.0635 0.889) (xy -0.03175 0.89916) (xy 0 0.9017)
						(xy 0.03175 0.89916) (xy 0.0635 0.889) (xy 0.09144 0.87376) (xy 0.11684 0.85344) (xy 0.13716 0.82804)
						(xy 0.1524 0.8001) (xy 0.16256 0.76835) (xy 0.1651 0.7366) (xy 0.1651 -0.13462) (xy 0.17272 -0.14224)
						(xy 0.19812 -0.1778) (xy 0.2032 -0.18796) (xy 0.20701 -0.19685) (xy 0.21209 -0.20701) (xy 0.2159 -0.21717)
						(xy 0.21844 -0.22733) (xy 0.22225 -0.23876) (xy 0.22352 -0.24892) (xy 0.22606 -0.25908) (xy 0.22733 -0.27051)
						(xy 0.22733 -0.28067) (xy 0.2286 -0.2921) (xy 0.22733 -0.30353) (xy 0.22733 -0.31369) (xy 0.22606 -0.32512)
						(xy 0.22352 -0.33528) (xy 0.22225 -0.34544) (xy 0.21844 -0.35687) (xy 0.2159 -0.36703) (xy 0.21209 -0.37719)
						(xy 0.20701 -0.38735) (xy 0.2032 -0.39624) (xy 0.19812 -0.4064) (xy 0.17272 -0.44196) (xy 0.1651 -0.44958)
						(xy 0.1651 -0.7366) (xy 0.16256 -0.76835) (xy 0.1524 -0.8001) (xy 0.13716 -0.82804) (xy 0.11684 -0.85344)
						(xy 0.09144 -0.87376) (xy 0.0635 -0.889) (xy 0.03175 -0.89916)
					)
					(width 0)
					(fill yes)
				)
			)
		)
	)
)
